(kicad_pcb
	(version 20260206)
	(generator "pcbnew")
	(generator_version "10.0")
	(general
		(thickness 1.6)
		(legacy_teardrops no)
	)
	(paper "A4")
	(title_block
		(title "04192023_DAF0TMB3IC0_F0TG_MB_C_brd_V02_OCP.brd")
		(comment 1 "Grand Teton / footprint 1808 of 8354 (J16), pads 227-291 of 291")
	)
	(layers
		(0 "F.Cu" signal "TOP")
		(4 "In1.Cu" signal "GND")
		(6 "In2.Cu" signal "IN1")
		(8 "In3.Cu" signal "GND1")
		(10 "In4.Cu" signal "IN2")
		(12 "In5.Cu" signal "GND2")
		(14 "In6.Cu" signal "IN3")
		(16 "In7.Cu" signal "GND3")
		(18 "In8.Cu" signal "VCC")
		(20 "In9.Cu" signal "VCC1")
		(22 "In10.Cu" signal "GND4")
		(24 "In11.Cu" signal "IN4")
		(26 "In12.Cu" signal "GND5")
		(28 "In13.Cu" signal "IN5")
		(30 "In14.Cu" signal "GND6")
		(32 "In15.Cu" signal "IN6")
		(34 "In16.Cu" signal "GND7")
		(2 "B.Cu" signal "BOTTOM")
		(9 "F.Adhes" user "F.Adhesive")
		(11 "B.Adhes" user "B.Adhesive")
		(13 "F.Paste" user "Package Geometry/Pastemask Top")
		(15 "B.Paste" user "Package Geometry/Pastemask Bottom")
		(5 "F.SilkS" user "Ref Des/Silkscreen Top")
		(7 "B.SilkS" user "Ref Des/Silkscreen Bottom")
		(1 "F.Mask" user "Board Geometry/Soldermask Top")
		(3 "B.Mask" user "Board Geometry/Soldermask Bottom")
		(17 "Dwgs.User" user "User.Drawings")
		(19 "Cmts.User" user "User.Comments")
		(21 "Eco1.User" user "User.Eco1")
		(23 "Eco2.User" user "User.Eco2")
		(25 "Edge.Cuts" user "Board Geometry/Outline")
		(27 "Margin" user)
		(31 "F.CrtYd" user "Package Geometry/Place Bound Top")
		(29 "B.CrtYd" user "Package Geometry/Place Bound Bottom")
		(35 "F.Fab" user "Ref Des/Assembly Top")
		(33 "B.Fab" user "Ref Des/Assembly Bottom")
	)
	(footprint ""
		(layer "F.Cu")
		(at 414.418018 -255.560068 180)
		(property "Reference" "J16"
			(at 1.474216 81.889092 0)
			(unlocked yes)
			(layer "F.SilkS")
			(effects
				(font
					(size 0.7874 0.5842)
					(thickness 0.1524)
				)
			)
		)
		(property "Value" ""
			(at 0 0 180)
			(layer "F.Fab")
			(effects
				(font
					(size 1.27 1.27)
				)
			)
		)
		(duplicate_pad_numbers_are_jumpers no)
		(pad "227" smd rect
			(at 2.050034 11.474958 90)
			(size 0.519938 1.4986)
			(layers "F.Cu" "F.Mask" "F.Paste")
			(net "M_G_CPU0_SB_PAR")
		)
		(pad "228" smd rect
			(at 2.050034 12.325096 90)
			(size 0.519938 1.4986)
			(layers "F.Cu" "F.Mask" "F.Paste")
			(net "GND")
		)
		(pad "229" smd rect
			(at 2.050034 13.17498 90)
			(size 0.519938 1.4986)
			(layers "F.Cu" "F.Mask" "F.Paste")
			(net "M_G_CPU0_SB_CS_N<1>")
		)
		(pad "230" smd rect
			(at 2.050034 14.025118 90)
			(size 0.519938 1.4986)
			(layers "F.Cu" "F.Mask" "F.Paste")
			(net "GND")
		)
		(pad "231" smd rect
			(at 2.050034 14.875002 90)
			(size 0.519938 1.4986)
			(layers "F.Cu" "F.Mask" "F.Paste")
			(net "Net_2338")
		)
		(pad "232" smd rect
			(at 2.050034 15.724886 90)
			(size 0.519938 1.4986)
			(layers "F.Cu" "F.Mask" "F.Paste")
			(net "Net_2339")
		)
		(pad "233" smd rect
			(at 2.050034 16.575024 90)
			(size 0.519938 1.4986)
			(layers "F.Cu" "F.Mask" "F.Paste")
			(net "GND")
		)
		(pad "234" smd rect
			(at 2.050034 17.424908 90)
			(size 0.519938 1.4986)
			(layers "F.Cu" "F.Mask" "F.Paste")
			(net "M_G_CPU0_SB_CB<6>")
		)
		(pad "235" smd rect
			(at 2.050034 18.275046 90)
			(size 0.519938 1.4986)
			(layers "F.Cu" "F.Mask" "F.Paste")
			(net "GND")
		)
		(pad "236" smd rect
			(at 2.050034 19.12493 90)
			(size 0.519938 1.4986)
			(layers "F.Cu" "F.Mask" "F.Paste")
			(net "M_G_CPU0_SB_CB<7>")
		)
		(pad "237" smd rect
			(at 2.050034 19.975068 90)
			(size 0.519938 1.4986)
			(layers "F.Cu" "F.Mask" "F.Paste")
			(net "GND")
		)
		(pad "238" smd rect
			(at 2.050034 20.824952 90)
			(size 0.519938 1.4986)
			(layers "F.Cu" "F.Mask" "F.Paste")
			(net "M_G_CPU0_SB_DQS_DN<4>")
		)
		(pad "239" smd rect
			(at 2.050034 21.67509 90)
			(size 0.519938 1.4986)
			(layers "F.Cu" "F.Mask" "F.Paste")
			(net "M_G_CPU0_SB_DQS_DP<4>")
		)
		(pad "240" smd rect
			(at 2.050034 22.524974 90)
			(size 0.519938 1.4986)
			(layers "F.Cu" "F.Mask" "F.Paste")
			(net "GND")
		)
		(pad "241" smd rect
			(at 2.050034 23.375112 90)
			(size 0.519938 1.4986)
			(layers "F.Cu" "F.Mask" "F.Paste")
			(net "M_G_CPU0_SB_CB<2>")
		)
		(pad "242" smd rect
			(at 2.050034 24.224996 90)
			(size 0.519938 1.4986)
			(layers "F.Cu" "F.Mask" "F.Paste")
			(net "GND")
		)
		(pad "243" smd rect
			(at 2.050034 25.07488 90)
			(size 0.519938 1.4986)
			(layers "F.Cu" "F.Mask" "F.Paste")
			(net "M_G_CPU0_SB_CB<3>")
		)
		(pad "244" smd rect
			(at 2.050034 25.925018 90)
			(size 0.519938 1.4986)
			(layers "F.Cu" "F.Mask" "F.Paste")
			(net "GND")
		)
		(pad "245" smd rect
			(at 2.050034 26.774902 90)
			(size 0.519938 1.4986)
			(layers "F.Cu" "F.Mask" "F.Paste")
			(net "M_G_CPU0_SB_DQ<2>")
		)
		(pad "246" smd rect
			(at 2.050034 27.62504 90)
			(size 0.519938 1.4986)
			(layers "F.Cu" "F.Mask" "F.Paste")
			(net "GND")
		)
		(pad "247" smd rect
			(at 2.050034 28.474924 90)
			(size 0.519938 1.4986)
			(layers "F.Cu" "F.Mask" "F.Paste")
			(net "M_G_CPU0_SB_DQ<3>")
		)
		(pad "248" smd rect
			(at 2.050034 29.325062 90)
			(size 0.519938 1.4986)
			(layers "F.Cu" "F.Mask" "F.Paste")
			(net "GND")
		)
		(pad "249" smd rect
			(at 2.050034 30.174946 90)
			(size 0.519938 1.4986)
			(layers "F.Cu" "F.Mask" "F.Paste")
			(net "M_G_CPU0_SB_DQS_DN<5>")
		)
		(pad "250" smd rect
			(at 2.050034 31.025084 90)
			(size 0.519938 1.4986)
			(layers "F.Cu" "F.Mask" "F.Paste")
			(net "M_G_CPU0_SB_DQS_DP<5>")
		)
		(pad "251" smd rect
			(at 2.050034 31.874968 90)
			(size 0.519938 1.4986)
			(layers "F.Cu" "F.Mask" "F.Paste")
			(net "GND")
		)
		(pad "252" smd rect
			(at 2.050034 32.725106 90)
			(size 0.519938 1.4986)
			(layers "F.Cu" "F.Mask" "F.Paste")
			(net "M_G_CPU0_SB_DQ<6>")
		)
		(pad "253" smd rect
			(at 2.050034 33.57499 90)
			(size 0.519938 1.4986)
			(layers "F.Cu" "F.Mask" "F.Paste")
			(net "GND")
		)
		(pad "254" smd rect
			(at 2.050034 34.425128 90)
			(size 0.519938 1.4986)
			(layers "F.Cu" "F.Mask" "F.Paste")
			(net "M_G_CPU0_SB_DQ<7>")
		)
		(pad "255" smd rect
			(at 2.050034 35.275012 90)
			(size 0.519938 1.4986)
			(layers "F.Cu" "F.Mask" "F.Paste")
			(net "GND")
		)
		(pad "256" smd rect
			(at 2.050034 36.124896 90)
			(size 0.519938 1.4986)
			(layers "F.Cu" "F.Mask" "F.Paste")
			(net "M_G_CPU0_SB_DQ<10>")
		)
		(pad "257" smd rect
			(at 2.050034 36.975034 90)
			(size 0.519938 1.4986)
			(layers "F.Cu" "F.Mask" "F.Paste")
			(net "GND")
		)
		(pad "258" smd rect
			(at 2.050034 37.824918 90)
			(size 0.519938 1.4986)
			(layers "F.Cu" "F.Mask" "F.Paste")
			(net "M_G_CPU0_SB_DQ<11>")
		)
		(pad "259" smd rect
			(at 2.050034 38.675056 90)
			(size 0.519938 1.4986)
			(layers "F.Cu" "F.Mask" "F.Paste")
			(net "GND")
		)
		(pad "260" smd rect
			(at 2.050034 39.52494 90)
			(size 0.519938 1.4986)
			(layers "F.Cu" "F.Mask" "F.Paste")
			(net "M_G_CPU0_SB_DQS_DN<6>")
		)
		(pad "261" smd rect
			(at 2.050034 40.375078 90)
			(size 0.519938 1.4986)
			(layers "F.Cu" "F.Mask" "F.Paste")
			(net "M_G_CPU0_SB_DQS_DP<6>")
		)
		(pad "262" smd rect
			(at 2.050034 41.224962 90)
			(size 0.519938 1.4986)
			(layers "F.Cu" "F.Mask" "F.Paste")
			(net "GND")
		)
		(pad "263" smd rect
			(at 2.050034 42.0751 90)
			(size 0.519938 1.4986)
			(layers "F.Cu" "F.Mask" "F.Paste")
			(net "M_G_CPU0_SB_DQ<14>")
		)
		(pad "264" smd rect
			(at 2.050034 42.924984 90)
			(size 0.519938 1.4986)
			(layers "F.Cu" "F.Mask" "F.Paste")
			(net "GND")
		)
		(pad "265" smd rect
			(at 2.050034 43.775122 90)
			(size 0.519938 1.4986)
			(layers "F.Cu" "F.Mask" "F.Paste")
			(net "M_G_CPU0_SB_DQ<15>")
		)
		(pad "266" smd rect
			(at 2.050034 44.625006 90)
			(size 0.519938 1.4986)
			(layers "F.Cu" "F.Mask" "F.Paste")
			(net "GND")
		)
		(pad "267" smd rect
			(at 2.050034 45.47489 90)
			(size 0.519938 1.4986)
			(layers "F.Cu" "F.Mask" "F.Paste")
			(net "M_G_CPU0_SB_DQ<18>")
		)
		(pad "268" smd rect
			(at 2.050034 46.325028 90)
			(size 0.519938 1.4986)
			(layers "F.Cu" "F.Mask" "F.Paste")
			(net "GND")
		)
		(pad "269" smd rect
			(at 2.050034 47.174912 90)
			(size 0.519938 1.4986)
			(layers "F.Cu" "F.Mask" "F.Paste")
			(net "M_G_CPU0_SB_DQ<19>")
		)
		(pad "270" smd rect
			(at 2.050034 48.02505 90)
			(size 0.519938 1.4986)
			(layers "F.Cu" "F.Mask" "F.Paste")
			(net "GND")
		)
		(pad "271" smd rect
			(at 2.050034 48.874934 90)
			(size 0.519938 1.4986)
			(layers "F.Cu" "F.Mask" "F.Paste")
			(net "M_G_CPU0_SB_DQS_DN<7>")
		)
		(pad "272" smd rect
			(at 2.050034 49.725072 90)
			(size 0.519938 1.4986)
			(layers "F.Cu" "F.Mask" "F.Paste")
			(net "M_G_CPU0_SB_DQS_DP<7>")
		)
		(pad "273" smd rect
			(at 2.050034 50.574956 90)
			(size 0.519938 1.4986)
			(layers "F.Cu" "F.Mask" "F.Paste")
			(net "GND")
		)
		(pad "274" smd rect
			(at 2.050034 51.425094 90)
			(size 0.519938 1.4986)
			(layers "F.Cu" "F.Mask" "F.Paste")
			(net "M_G_CPU0_SB_DQ<22>")
		)
		(pad "275" smd rect
			(at 2.050034 52.274978 90)
			(size 0.519938 1.4986)
			(layers "F.Cu" "F.Mask" "F.Paste")
			(net "GND")
		)
		(pad "276" smd rect
			(at 2.050034 53.125116 90)
			(size 0.519938 1.4986)
			(layers "F.Cu" "F.Mask" "F.Paste")
			(net "M_G_CPU0_SB_DQ<23>")
		)
		(pad "277" smd rect
			(at 2.050034 53.975 90)
			(size 0.519938 1.4986)
			(layers "F.Cu" "F.Mask" "F.Paste")
			(net "GND")
		)
		(pad "278" smd rect
			(at 2.050034 54.824884 90)
			(size 0.519938 1.4986)
			(layers "F.Cu" "F.Mask" "F.Paste")
			(net "M_G_CPU0_SB_DQ<26>")
		)
		(pad "279" smd rect
			(at 2.050034 55.675022 90)
			(size 0.519938 1.4986)
			(layers "F.Cu" "F.Mask" "F.Paste")
			(net "GND")
		)
		(pad "280" smd rect
			(at 2.050034 56.524906 90)
			(size 0.519938 1.4986)
			(layers "F.Cu" "F.Mask" "F.Paste")
			(net "M_G_CPU0_SB_DQ<27>")
		)
		(pad "281" smd rect
			(at 2.050034 57.375044 90)
			(size 0.519938 1.4986)
			(layers "F.Cu" "F.Mask" "F.Paste")
			(net "GND")
		)
		(pad "282" smd rect
			(at 2.050034 58.224928 90)
			(size 0.519938 1.4986)
			(layers "F.Cu" "F.Mask" "F.Paste")
			(net "M_G_CPU0_SB_DQS_DN<8>")
		)
		(pad "283" smd rect
			(at 2.050034 59.075066 90)
			(size 0.519938 1.4986)
			(layers "F.Cu" "F.Mask" "F.Paste")
			(net "M_G_CPU0_SB_DQS_DP<8>")
		)
		(pad "284" smd rect
			(at 2.050034 59.92495 90)
			(size 0.519938 1.4986)
			(layers "F.Cu" "F.Mask" "F.Paste")
			(net "GND")
		)
		(pad "285" smd rect
			(at 2.050034 60.775088 90)
			(size 0.519938 1.4986)
			(layers "F.Cu" "F.Mask" "F.Paste")
			(net "M_G_CPU0_SB_DQ<30>")
		)
		(pad "286" smd rect
			(at 2.050034 61.624972 90)
			(size 0.519938 1.4986)
			(layers "F.Cu" "F.Mask" "F.Paste")
			(net "GND")
		)
		(pad "287" smd rect
			(at 2.050034 62.47511 90)
			(size 0.519938 1.4986)
			(layers "F.Cu" "F.Mask" "F.Paste")
			(net "M_G_CPU0_SB_DQ<31>")
		)
		(pad "288" smd rect
			(at 2.050034 63.324994 90)
			(size 0.519938 1.4986)
			(layers "F.Cu" "F.Mask" "F.Paste")
			(net "GND")
		)
		(pad "G1" thru_hole oval
			(at 0 -68.97497 90)
			(size 1.7272 3.4798)
			(drill oval 1.2192 2.4638)
			(layers "*.Cu" "*.Mask")
			(remove_unused_layers no)
			(net "GND")
			(clearance 0.127)
			(thermal_gap 0.127)
		)
		(pad "G2" thru_hole oval
			(at 0 3.875024 90)
			(size 1.7272 3.4798)
			(drill oval 1.2192 2.4638)
			(layers "*.Cu" "*.Mask")
			(remove_unused_layers no)
			(net "GND")
			(clearance 0.127)
			(thermal_gap 0.127)
		)
		(pad "G3" thru_hole oval
			(at 0 68.97497 90)
			(size 1.7272 3.4798)
			(drill oval 1.2192 2.4638)
			(layers "*.Cu" "*.Mask")
			(remove_unused_layers no)
			(net "GND")
			(clearance 0.127)
			(thermal_gap 0.127)
		)
	)
)
